(kicad_pcb
	(version 20260206)
	(generator "pcbnew")
	(generator_version "10.0")
	(general
		(thickness 1.6)
		(legacy_teardrops no)
	)
	(paper "A4")
	(title_block
		(title "01162023_DA0F0TEBIF0_F0T_Expander_BD_F_brd_V02_OCP.brd")
		(comment 1 "Grand Teton / footprints 4678-4684 of 9728")
	)
	(layers
		(0 "F.Cu" signal "TOP")
		(4 "In1.Cu" signal "GND")
		(6 "In2.Cu" signal "VCC")
		(8 "In3.Cu" signal "VCC1")
		(10 "In4.Cu" signal "GND1")
		(12 "In5.Cu" signal "IN1")
		(14 "In6.Cu" signal "GND2")
		(16 "In7.Cu" signal "IN2")
		(18 "In8.Cu" signal "GND3")
		(20 "In9.Cu" signal "IN3")
		(22 "In10.Cu" signal "GND4")
		(24 "In11.Cu" signal "IN4")
		(26 "In12.Cu" signal "GND5")
		(28 "In13.Cu" signal "IN5")
		(30 "In14.Cu" signal "GND6")
		(32 "In15.Cu" signal "IN6")
		(34 "In16.Cu" signal "GND7")
		(2 "B.Cu" signal "BOTTOM")
		(9 "F.Adhes" user "F.Adhesive")
		(11 "B.Adhes" user "B.Adhesive")
		(13 "F.Paste" user "Package Geometry/Pastemask Top")
		(15 "B.Paste" user "Package Geometry/Pastemask Bottom")
		(5 "F.SilkS" user "Ref Des/Silkscreen Top")
		(7 "B.SilkS" user "Ref Des/Silkscreen Bottom")
		(1 "F.Mask" user "Board Geometry/Soldermask Top")
		(3 "B.Mask" user "Board Geometry/Soldermask Bottom")
		(17 "Dwgs.User" user "User.Drawings")
		(19 "Cmts.User" user "User.Comments")
		(21 "Eco1.User" user "User.Eco1")
		(23 "Eco2.User" user "User.Eco2")
		(25 "Edge.Cuts" user "Board Geometry/Outline")
		(27 "Margin" user)
		(31 "F.CrtYd" user "Package Geometry/Place Bound Top")
		(29 "B.CrtYd" user "Package Geometry/Place Bound Bottom")
		(35 "F.Fab" user "Ref Des/Assembly Top")
		(33 "B.Fab" user "Ref Des/Assembly Bottom")
	)
	(footprint ""
		(layer "F.Cu")
		(at 280.571448 -407.714958 90)
		(property "Reference" "C2747"
			(at 0 0 90)
			(layer "F.SilkS")
			(hide yes)
			(effects
				(font
					(size 1.27 1.27)
				)
			)
		)
		(property "Value" ""
			(at 0 0 90)
			(layer "F.Fab")
			(effects
				(font
					(size 1.27 1.27)
				)
			)
		)
		(duplicate_pad_numbers_are_jumpers no)
		(fp_line
			(start 0.7874 -0.4064)
			(end 0.7874 0.4064)
			(stroke
				(width 0.1524)
				(type default)
			)
			(layer "F.SilkS")
		)
		(fp_line
			(start -0.7874 -0.4064)
			(end 0.7874 -0.4064)
			(stroke
				(width 0.1524)
				(type default)
			)
			(layer "F.SilkS")
		)
		(fp_line
			(start 0.7874 0.4064)
			(end -0.7874 0.4064)
			(stroke
				(width 0.1524)
				(type default)
			)
			(layer "F.SilkS")
		)
		(fp_line
			(start -0.7874 0.4064)
			(end -0.7874 -0.4064)
			(stroke
				(width 0.1524)
				(type default)
			)
			(layer "F.SilkS")
		)
		(fp_line
			(start -0.12065 -0.305054)
			(end -0.12065 -0.2794)
			(stroke
				(width 0.1)
				(type default)
			)
			(layer "F.Fab")
		)
		(fp_line
			(start -0.67945 -0.305054)
			(end -0.12065 -0.305054)
			(stroke
				(width 0.1)
				(type default)
			)
			(layer "F.Fab")
		)
		(fp_line
			(start 0.67945 -0.3048)
			(end 0.67945 0.3048)
			(stroke
				(width 0.1)
				(type default)
			)
			(layer "F.Fab")
		)
		(fp_line
			(start 0.12065 -0.3048)
			(end 0.67945 -0.3048)
			(stroke
				(width 0.1)
				(type default)
			)
			(layer "F.Fab")
		)
		(fp_line
			(start 0.12065 -0.2794)
			(end 0.12065 -0.3048)
			(stroke
				(width 0.1)
				(type default)
			)
			(layer "F.Fab")
		)
		(fp_line
			(start -0.12065 -0.2794)
			(end 0.12065 -0.2794)
			(stroke
				(width 0.1)
				(type default)
			)
			(layer "F.Fab")
		)
		(fp_line
			(start 0.120396 0.2794)
			(end -0.12065 0.2794)
			(stroke
				(width 0.1)
				(type default)
			)
			(layer "F.Fab")
		)
		(fp_line
			(start -0.12065 0.2794)
			(end -0.12065 0.3048)
			(stroke
				(width 0.1)
				(type default)
			)
			(layer "F.Fab")
		)
		(fp_line
			(start 0.67945 0.3048)
			(end 0.120396 0.3048)
			(stroke
				(width 0.1)
				(type default)
			)
			(layer "F.Fab")
		)
		(fp_line
			(start 0.120396 0.3048)
			(end 0.120396 0.2794)
			(stroke
				(width 0.1)
				(type default)
			)
			(layer "F.Fab")
		)
		(fp_line
			(start -0.12065 0.3048)
			(end -0.67945 0.3048)
			(stroke
				(width 0.1)
				(type default)
			)
			(layer "F.Fab")
		)
		(fp_line
			(start -0.67945 0.3048)
			(end -0.67945 -0.305054)
			(stroke
				(width 0.1)
				(type default)
			)
			(layer "F.Fab")
		)
		(pad "1" smd circle
			(at -0.40005 0 90)
			(size 0 0)
			(layers "F.Cu" "F.Mask" "F.Paste")
			(net "P3V3_AUX")
		)
		(pad "2" smd circle
			(at 0.40005 0 90)
			(size 0 0)
			(layers "F.Cu" "F.Mask" "F.Paste")
			(net "GND")
		)
	)
	(footprint ""
		(layer "F.Cu")
		(at 385.308602 -247.32996 180)
		(property "Reference" "C2577"
			(at 0 0 180)
			(layer "F.SilkS")
			(hide yes)
			(effects
				(font
					(size 1.27 1.27)
				)
			)
		)
		(property "Value" ""
			(at 0 0 180)
			(layer "F.Fab")
			(effects
				(font
					(size 1.27 1.27)
				)
			)
		)
		(duplicate_pad_numbers_are_jumpers no)
		(fp_line
			(start 1.2954 0.5842)
			(end -1.2954 0.5842)
			(stroke
				(width 0.1524)
				(type default)
			)
			(layer "F.SilkS")
		)
		(fp_line
			(start 1.2954 -0.5842)
			(end 1.2954 0.5842)
			(stroke
				(width 0.1524)
				(type default)
			)
			(layer "F.SilkS")
		)
		(fp_line
			(start -1.2954 0.5842)
			(end -1.2954 -0.5842)
			(stroke
				(width 0.1524)
				(type default)
			)
			(layer "F.SilkS")
		)
		(fp_line
			(start -1.2954 -0.5842)
			(end 1.2954 -0.5842)
			(stroke
				(width 0.1524)
				(type default)
			)
			(layer "F.SilkS")
		)
		(fp_line
			(start 1.1938 0.4064)
			(end 0.8636 0.4064)
			(stroke
				(width 0.1)
				(type default)
			)
			(layer "F.Fab")
		)
		(fp_line
			(start 1.1938 -0.4064)
			(end 1.1938 0.4064)
			(stroke
				(width 0.1)
				(type default)
			)
			(layer "F.Fab")
		)
		(fp_line
			(start 0.8636 0.4572)
			(end -0.8636 0.4572)
			(stroke
				(width 0.1)
				(type default)
			)
			(layer "F.Fab")
		)
		(fp_line
			(start 0.8636 0.4064)
			(end 0.8636 0.4572)
			(stroke
				(width 0.1)
				(type default)
			)
			(layer "F.Fab")
		)
		(fp_line
			(start 0.8636 -0.4064)
			(end 1.1938 -0.4064)
			(stroke
				(width 0.1)
				(type default)
			)
			(layer "F.Fab")
		)
		(fp_line
			(start 0.8636 -0.4572)
			(end 0.8636 -0.4064)
			(stroke
				(width 0.1)
				(type default)
			)
			(layer "F.Fab")
		)
		(fp_line
			(start -0.8636 0.4572)
			(end -0.8636 0.4064)
			(stroke
				(width 0.1)
				(type default)
			)
			(layer "F.Fab")
		)
		(fp_line
			(start -0.8636 0.4064)
			(end -1.1938 0.4064)
			(stroke
				(width 0.1)
				(type default)
			)
			(layer "F.Fab")
		)
		(fp_line
			(start -0.8636 -0.4064)
			(end -0.8636 -0.4572)
			(stroke
				(width 0.1)
				(type default)
			)
			(layer "F.Fab")
		)
		(fp_line
			(start -0.8636 -0.4572)
			(end 0.8636 -0.4572)
			(stroke
				(width 0.1)
				(type default)
			)
			(layer "F.Fab")
		)
		(fp_line
			(start -1.1938 0.4064)
			(end -1.1938 -0.4064)
			(stroke
				(width 0.1)
				(type default)
			)
			(layer "F.Fab")
		)
		(fp_line
			(start -1.1938 -0.4064)
			(end -0.8636 -0.4064)
			(stroke
				(width 0.1)
				(type default)
			)
			(layer "F.Fab")
		)
		(pad "1" smd rect
			(at -0.7366 0 90)
			(size 0.7112 0.8128)
			(layers "F.Cu" "F.Mask" "F.Paste")
			(net "P1V8_SDB_VCORE")
		)
		(pad "2" smd rect
			(at 0.7366 0 90)
			(size 0.7112 0.8128)
			(layers "F.Cu" "F.Mask" "F.Paste")
			(net "GND")
		)
	)
	(footprint ""
		(layer "F.Cu")
		(at 440.687206 -300.650402 -90)
		(property "Reference" "R3996"
			(at 0 0 270)
			(layer "F.SilkS")
			(hide yes)
			(effects
				(font
					(size 1.27 1.27)
				)
			)
		)
		(property "Value" ""
			(at 0 0 270)
			(layer "F.Fab")
			(effects
				(font
					(size 1.27 1.27)
				)
			)
		)
		(duplicate_pad_numbers_are_jumpers no)
		(fp_line
			(start -0.7874 0.4064)
			(end -0.7874 -0.4064)
			(stroke
				(width 0.1524)
				(type default)
			)
			(layer "F.SilkS")
		)
		(fp_line
			(start 0.7874 0.4064)
			(end -0.7874 0.4064)
			(stroke
				(width 0.1524)
				(type default)
			)
			(layer "F.SilkS")
		)
		(fp_line
			(start -0.7874 -0.4064)
			(end 0.7874 -0.4064)
			(stroke
				(width 0.1524)
				(type default)
			)
			(layer "F.SilkS")
		)
		(fp_line
			(start 0.7874 -0.4064)
			(end 0.7874 0.4064)
			(stroke
				(width 0.1524)
				(type default)
			)
			(layer "F.SilkS")
		)
		(fp_line
			(start -0.67945 0.3048)
			(end -0.67945 -0.305054)
			(stroke
				(width 0.1)
				(type default)
			)
			(layer "F.Fab")
		)
		(fp_line
			(start -0.12065 0.3048)
			(end -0.67945 0.3048)
			(stroke
				(width 0.1)
				(type default)
			)
			(layer "F.Fab")
		)
		(fp_line
			(start 0.120396 0.3048)
			(end 0.120396 0.2794)
			(stroke
				(width 0.1)
				(type default)
			)
			(layer "F.Fab")
		)
		(fp_line
			(start 0.67945 0.3048)
			(end 0.120396 0.3048)
			(stroke
				(width 0.1)
				(type default)
			)
			(layer "F.Fab")
		)
		(fp_line
			(start -0.12065 0.2794)
			(end -0.12065 0.3048)
			(stroke
				(width 0.1)
				(type default)
			)
			(layer "F.Fab")
		)
		(fp_line
			(start 0.120396 0.2794)
			(end -0.12065 0.2794)
			(stroke
				(width 0.1)
				(type default)
			)
			(layer "F.Fab")
		)
		(fp_line
			(start -0.12065 -0.2794)
			(end 0.12065 -0.2794)
			(stroke
				(width 0.1)
				(type default)
			)
			(layer "F.Fab")
		)
		(fp_line
			(start 0.12065 -0.2794)
			(end 0.12065 -0.3048)
			(stroke
				(width 0.1)
				(type default)
			)
			(layer "F.Fab")
		)
		(fp_line
			(start 0.12065 -0.3048)
			(end 0.67945 -0.3048)
			(stroke
				(width 0.1)
				(type default)
			)
			(layer "F.Fab")
		)
		(fp_line
			(start 0.67945 -0.3048)
			(end 0.67945 0.3048)
			(stroke
				(width 0.1)
				(type default)
			)
			(layer "F.Fab")
		)
		(fp_line
			(start -0.67945 -0.305054)
			(end -0.12065 -0.305054)
			(stroke
				(width 0.1)
				(type default)
			)
			(layer "F.Fab")
		)
		(fp_line
			(start -0.12065 -0.305054)
			(end -0.12065 -0.2794)
			(stroke
				(width 0.1)
				(type default)
			)
			(layer "F.Fab")
		)
		(pad "1" smd circle
			(at -0.40005 0 270)
			(size 0 0)
			(layers "F.Cu" "F.Mask" "F.Paste")
			(net "I2C0_PEX3_SHPC_SCL")
		)
		(pad "2" smd circle
			(at 0.40005 0 270)
			(size 0 0)
			(layers "F.Cu" "F.Mask" "F.Paste")
			(net "I2C_PEX3_HOST_SCL")
		)
	)
	(footprint ""
		(layer "F.Cu")
		(at 437.302148 -306.074572 90)
		(property "Reference" "R1439"
			(at 0 0 90)
			(layer "F.SilkS")
			(hide yes)
			(effects
				(font
					(size 1.27 1.27)
				)
			)
		)
		(property "Value" ""
			(at 0 0 90)
			(layer "F.Fab")
			(effects
				(font
					(size 1.27 1.27)
				)
			)
		)
		(duplicate_pad_numbers_are_jumpers no)
		(fp_line
			(start 0.7874 -0.4064)
			(end 0.7874 0.4064)
			(stroke
				(width 0.1524)
				(type default)
			)
			(layer "F.SilkS")
		)
		(fp_line
			(start -0.7874 -0.4064)
			(end 0.7874 -0.4064)
			(stroke
				(width 0.1524)
				(type default)
			)
			(layer "F.SilkS")
		)
		(fp_line
			(start 0.7874 0.4064)
			(end -0.7874 0.4064)
			(stroke
				(width 0.1524)
				(type default)
			)
			(layer "F.SilkS")
		)
		(fp_line
			(start -0.7874 0.4064)
			(end -0.7874 -0.4064)
			(stroke
				(width 0.1524)
				(type default)
			)
			(layer "F.SilkS")
		)
		(fp_line
			(start -0.12065 -0.305054)
			(end -0.12065 -0.2794)
			(stroke
				(width 0.1)
				(type default)
			)
			(layer "F.Fab")
		)
		(fp_line
			(start -0.67945 -0.305054)
			(end -0.12065 -0.305054)
			(stroke
				(width 0.1)
				(type default)
			)
			(layer "F.Fab")
		)
		(fp_line
			(start 0.67945 -0.3048)
			(end 0.67945 0.3048)
			(stroke
				(width 0.1)
				(type default)
			)
			(layer "F.Fab")
		)
		(fp_line
			(start 0.12065 -0.3048)
			(end 0.67945 -0.3048)
			(stroke
				(width 0.1)
				(type default)
			)
			(layer "F.Fab")
		)
		(fp_line
			(start 0.12065 -0.2794)
			(end 0.12065 -0.3048)
			(stroke
				(width 0.1)
				(type default)
			)
			(layer "F.Fab")
		)
		(fp_line
			(start -0.12065 -0.2794)
			(end 0.12065 -0.2794)
			(stroke
				(width 0.1)
				(type default)
			)
			(layer "F.Fab")
		)
		(fp_line
			(start 0.120396 0.2794)
			(end -0.12065 0.2794)
			(stroke
				(width 0.1)
				(type default)
			)
			(layer "F.Fab")
		)
		(fp_line
			(start -0.12065 0.2794)
			(end -0.12065 0.3048)
			(stroke
				(width 0.1)
				(type default)
			)
			(layer "F.Fab")
		)
		(fp_line
			(start 0.67945 0.3048)
			(end 0.120396 0.3048)
			(stroke
				(width 0.1)
				(type default)
			)
			(layer "F.Fab")
		)
		(fp_line
			(start 0.120396 0.3048)
			(end 0.120396 0.2794)
			(stroke
				(width 0.1)
				(type default)
			)
			(layer "F.Fab")
		)
		(fp_line
			(start -0.12065 0.3048)
			(end -0.67945 0.3048)
			(stroke
				(width 0.1)
				(type default)
			)
			(layer "F.Fab")
		)
		(fp_line
			(start -0.67945 0.3048)
			(end -0.67945 -0.305054)
			(stroke
				(width 0.1)
				(type default)
			)
			(layer "F.Fab")
		)
		(pad "1" smd circle
			(at -0.40005 0 90)
			(size 0 0)
			(layers "F.Cu" "F.Mask" "F.Paste")
			(net "PEX3_SPARE4")
		)
		(pad "2" smd circle
			(at 0.40005 0 90)
			(size 0 0)
			(layers "F.Cu" "F.Mask" "F.Paste")
			(net "P1V8_PEX")
		)
	)
	(footprint ""
		(layer "F.Cu")
		(at 277.198582 -350.098614 90)
		(property "Reference" "C2349"
			(at 0 0 90)
			(layer "F.SilkS")
			(hide yes)
			(effects
				(font
					(size 1.27 1.27)
				)
			)
		)
		(property "Value" ""
			(at 0 0 90)
			(layer "F.Fab")
			(effects
				(font
					(size 1.27 1.27)
				)
			)
		)
		(duplicate_pad_numbers_are_jumpers no)
		(fp_line
			(start 0.299974 -0.150114)
			(end 0.299974 0.150114)
			(stroke
				(width 0.1)
				(type default)
			)
			(layer "F.Fab")
		)
		(fp_line
			(start -0.299974 -0.150114)
			(end 0.299974 -0.150114)
			(stroke
				(width 0.1)
				(type default)
			)
			(layer "F.Fab")
		)
		(fp_line
			(start 0.299974 0.150114)
			(end -0.299974 0.150114)
			(stroke
				(width 0.1)
				(type default)
			)
			(layer "F.Fab")
		)
		(fp_line
			(start -0.299974 0.150114)
			(end -0.299974 -0.150114)
			(stroke
				(width 0.1)
				(type default)
			)
			(layer "F.Fab")
		)
		(pad "1" smd rect
			(at -0.2667 0 90)
			(size 0.3048 0.381)
			(layers "F.Cu" "F.Mask" "F.Paste")
			(net "P5E_PEX2_STN4_TX_DP<75>")
		)
		(pad "2" smd rect
			(at 0.2667 0 90)
			(size 0.3048 0.381)
			(layers "F.Cu" "F.Mask" "F.Paste")
			(net "P5E_PEX2_STN4_TX_C_DP<75>")
		)
	)
	(footprint ""
		(layer "F.Cu")
		(at 381.40386 -350.098614 90)
		(property "Reference" "C771"
			(at 0 0 90)
			(layer "F.SilkS")
			(hide yes)
			(effects
				(font
					(size 1.27 1.27)
				)
			)
		)
		(property "Value" ""
			(at 0 0 90)
			(layer "F.Fab")
			(effects
				(font
					(size 1.27 1.27)
				)
			)
		)
		(duplicate_pad_numbers_are_jumpers no)
		(fp_line
			(start 0.299974 -0.150114)
			(end 0.299974 0.150114)
			(stroke
				(width 0.1)
				(type default)
			)
			(layer "F.Fab")
		)
		(fp_line
			(start -0.299974 -0.150114)
			(end 0.299974 -0.150114)
			(stroke
				(width 0.1)
				(type default)
			)
			(layer "F.Fab")
		)
		(fp_line
			(start 0.299974 0.150114)
			(end -0.299974 0.150114)
			(stroke
				(width 0.1)
				(type default)
			)
			(layer "F.Fab")
		)
		(fp_line
			(start -0.299974 0.150114)
			(end -0.299974 -0.150114)
			(stroke
				(width 0.1)
				(type default)
			)
			(layer "F.Fab")
		)
		(pad "1" smd rect
			(at -0.2667 0 90)
			(size 0.3048 0.381)
			(layers "F.Cu" "F.Mask" "F.Paste")
			(net "P5E_PEX3_STN6_TX_DN<107>")
		)
		(pad "2" smd rect
			(at 0.2667 0 90)
			(size 0.3048 0.381)
			(layers "F.Cu" "F.Mask" "F.Paste")
			(net "P5E_PEX3_STN6_TX_C_DN<107>")
		)
	)
	(footprint ""
		(layer "F.Cu")
		(at 87.194644 -439.060082 180)
		(property "Reference" "X14"
			(at -0.1778 -1.92913 180)
			(unlocked yes)
			(layer "F.SilkS")
			(effects
				(font
					(size 0.7874 0.5842)
					(thickness 0.1524)
				)
				(justify left)
			)
		)
		(property "Value" ""
			(at 0 0 180)
			(layer "F.Fab")
			(effects
				(font
					(size 1.27 1.27)
				)
			)
		)
		(property "User Part Number" "TP15"
			(at 1.30175 1.27 270)
			(unlocked yes)
			(layer "Cmts.User")
			(hide yes)
			(effects
				(font
					(size 0.635 0.4064)
					(thickness 0.1524)
				)
			)
		)
		(property "Device Type" "TP_TDR_4P_FTS_MPKT4_H025P0200_IO_TP15_TP_TDR_4P_DIP"
			(at 1.30175 1.27 270)
			(unlocked yes)
			(layer "F.Fab")
			(hide yes)
			(effects
				(font
					(size 0.635 0.4064)
					(thickness 0.1524)
				)
			)
		)
		(duplicate_pad_numbers_are_jumpers no)
		(fp_line
			(start 2.54 3.81)
			(end 2.54 3.6703)
			(stroke
				(width 0.1524)
				(type default)
			)
			(layer "F.SilkS")
		)
		(fp_line
			(start 2.54 1.4097)
			(end 2.54 1.1303)
			(stroke
				(width 0.1524)
				(type default)
			)
			(layer "F.SilkS")
		)
		(fp_line
			(start 2.54 -1.1303)
			(end 2.54 -1.27)
			(stroke
				(width 0.1524)
				(type default)
			)
			(layer "F.SilkS")
		)
		(fp_line
			(start 2.54 -1.27)
			(end 0 -1.27)
			(stroke
				(width 0.1524)
				(type default)
			)
			(layer "F.SilkS")
		)
		(fp_line
			(start 0 3.81)
			(end 2.54 3.81)
			(stroke
				(width 0.1524)
				(type default)
			)
			(layer "F.SilkS")
		)
		(fp_line
			(start 0 3.175)
			(end 0 3.81)
			(stroke
				(width 0.1524)
				(type default)
			)
			(layer "F.SilkS")
		)
		(fp_line
			(start 0 0.635)
			(end 0 1.905)
			(stroke
				(width 0.1524)
				(type default)
			)
			(layer "F.SilkS")
		)
		(fp_line
			(start 0 -1.27)
			(end 0 -0.635)
			(stroke
				(width 0.1524)
				(type default)
			)
			(layer "F.SilkS")
		)
		(fp_poly
			(pts
				(xy -0.761746 0) (xy -2.285746 -0.762) (xy -2.285746 0.762)
			)
			(stroke
				(width 0)
				(type default)
			)
			(fill yes)
			(layer "F.SilkS")
		)
		(fp_line
			(start 2.54 3.81)
			(end 2.54 -1.27)
			(stroke
				(width 0.1)
				(type default)
			)
			(layer "F.Fab")
		)
		(fp_line
			(start 2.54 -1.27)
			(end 0 -1.27)
			(stroke
				(width 0.1)
				(type default)
			)
			(layer "F.Fab")
		)
		(fp_line
			(start 0 3.81)
			(end 2.54 3.81)
			(stroke
				(width 0.1)
				(type default)
			)
			(layer "F.Fab")
		)
		(fp_line
			(start 0 -1.27)
			(end 0 3.81)
			(stroke
				(width 0.1)
				(type default)
			)
			(layer "F.Fab")
		)
		(fp_poly
			(pts
				(xy -0.761746 0) (xy -2.285746 -0.762) (xy -2.285746 0.762)
			)
			(stroke
				(width 0)
				(type default)
			)
			(fill yes)
			(layer "F.Fab")
		)
		(pad "1" thru_hole circle
			(at 0 0 180)
			(size 1.0033 1.0033)
			(drill 0.249936)
			(layers "*.Cu" "*.Mask")
			(remove_unused_layers no)
			(net "TDR_DIFF_85_IN2_DIP")
			(clearance 0.10795)
			(thermal_gap 0.10795)
			(padstack
				(mode front_inner_back)
				(layer "Inner"
					(shape circle)
					(size 0.8001 0.8001)
					(clearance 0.1524)
				)
				(layer "B.Cu"
					(shape circle)
					(size 1.0033 1.0033)
					(clearance 0.10795)
				)
			)
		)
		(pad "2" thru_hole circle
			(at 2.54 0 180)
			(size 1.9939 1.9939)
			(drill 0.249936)
			(layers "*.Cu" "*.Mask")
			(remove_unused_layers no)
			(net "COUPON_GND1")
			(clearance 0.10795)
			(thermal_gap 0.10795)
			(padstack
				(mode front_inner_back)
				(layer "Inner"
					(shape circle)
					(size 0.8001 0.8001)
					(clearance 0.1524)
				)
				(layer "B.Cu"
					(shape circle)
					(size 1.9939 1.9939)
					(clearance 0.10795)
				)
			)
		)
		(pad "3" thru_hole circle
			(at 2.54 2.54 180)
			(size 1.9939 1.9939)
			(drill 0.249936)
			(layers "*.Cu" "*.Mask")
			(remove_unused_layers no)
			(net "COUPON_GND1")
			(clearance 0.10795)
			(thermal_gap 0.10795)
			(padstack
				(mode front_inner_back)
				(layer "Inner"
					(shape circle)
					(size 0.8001 0.8001)
					(clearance 0.1524)
				)
				(layer "B.Cu"
					(shape circle)
					(size 1.9939 1.9939)
					(clearance 0.10795)
				)
			)
		)
		(pad "4" thru_hole circle
			(at 0 2.54 180)
			(size 1.0033 1.0033)
			(drill 0.249936)
			(layers "*.Cu" "*.Mask")
			(remove_unused_layers no)
			(net "TDR_DIFF_85_IN2_DIN")
			(clearance 0.10795)
			(thermal_gap 0.10795)
			(padstack
				(mode front_inner_back)
				(layer "Inner"
					(shape circle)
					(size 0.8001 0.8001)
					(clearance 0.1524)
				)
				(layer "B.Cu"
					(shape circle)
					(size 1.0033 1.0033)
					(clearance 0.10795)
				)
			)
		)
	)
)
